# T6G (Grand Teton) — schematic netlist excerpt (pin names and nets, part order shuffled) for the footprints in the layout excerpt that follows; sources: Cadence DE-HDL packaged netlist, KiCad conversion of 04192023_DAF0TMB3IC0_F0TG_MB_C_brd_V02_OCP.brd

R3726  Q_RES  2.2K 5% CHIP  pkg 0402LF  page 252 : A = P3V3_AUX ; B = SMB_LM75_0_3V3AUX_SDA
R1425  Q_RES  0 5% CHIP  pkg 0402LF  page 164 : A = UART_CPU0_SCM_LVC3_UART1_R_TX ; B = UART_CPU0_SCM_LVC3_UART1_TX

(kicad_pcb
	(version 20260206)
	(generator "pcbnew")
	(generator_version "10.0")
	(general
		(thickness 1.6)
		(legacy_teardrops no)
	)
	(paper "A4")
	(title_block
		(title "04192023_DAF0TMB3IC0_F0TG_MB_C_brd_V02_OCP.brd")
		(comment 1 "Grand Teton / footprints 4839-4840 of 8354")
	)
	(layers
		(0 "F.Cu" signal "TOP")
		(4 "In1.Cu" signal "GND")
		(6 "In2.Cu" signal "IN1")
		(8 "In3.Cu" signal "GND1")
		(10 "In4.Cu" signal "IN2")
		(12 "In5.Cu" signal "GND2")
		(14 "In6.Cu" signal "IN3")
		(16 "In7.Cu" signal "GND3")
		(18 "In8.Cu" signal "VCC")
		(20 "In9.Cu" signal "VCC1")
		(22 "In10.Cu" signal "GND4")
		(24 "In11.Cu" signal "IN4")
		(26 "In12.Cu" signal "GND5")
		(28 "In13.Cu" signal "IN5")
		(30 "In14.Cu" signal "GND6")
		(32 "In15.Cu" signal "IN6")
		(34 "In16.Cu" signal "GND7")
		(2 "B.Cu" signal "BOTTOM")
		(9 "F.Adhes" user "F.Adhesive")
		(11 "B.Adhes" user "B.Adhesive")
		(13 "F.Paste" user "Package Geometry/Pastemask Top")
		(15 "B.Paste" user "Package Geometry/Pastemask Bottom")
		(5 "F.SilkS" user "Ref Des/Silkscreen Top")
		(7 "B.SilkS" user "Ref Des/Silkscreen Bottom")
		(1 "F.Mask" user "Board Geometry/Soldermask Top")
		(3 "B.Mask" user "Board Geometry/Soldermask Bottom")
		(17 "Dwgs.User" user "User.Drawings")
		(19 "Cmts.User" user "User.Comments")
		(21 "Eco1.User" user "User.Eco1")
		(23 "Eco2.User" user "User.Eco2")
		(25 "Edge.Cuts" user "Board Geometry/Outline")
		(27 "Margin" user)
		(31 "F.CrtYd" user "Package Geometry/Place Bound Top")
		(29 "B.CrtYd" user "Package Geometry/Place Bound Bottom")
		(35 "F.Fab" user "Ref Des/Assembly Top")
		(33 "B.Fab" user "Ref Des/Assembly Bottom")
	)
	(footprint ""
		(layer "F.Cu")
		(at 254.592836 -120.31345)
		(property "Reference" "R3726"
			(at 0 0 0)
			(layer "F.SilkS")
			(hide yes)
			(effects
				(font
					(size 1.27 1.27)
				)
			)
		)
		(property "Value" ""
			(at 0 0 0)
			(layer "F.Fab")
			(effects
				(font
					(size 1.27 1.27)
				)
			)
		)
		(duplicate_pad_numbers_are_jumpers no)
		(fp_line
			(start -0.7874 -0.4064)
			(end 0.7874 -0.4064)
			(stroke
				(width 0.1524)
				(type default)
			)
			(layer "F.SilkS")
		)
		(fp_line
			(start -0.7874 0.4064)
			(end -0.7874 -0.4064)
			(stroke
				(width 0.1524)
				(type default)
			)
			(layer "F.SilkS")
		)
		(fp_line
			(start 0.7874 -0.4064)
			(end 0.7874 0.4064)
			(stroke
				(width 0.1524)
				(type default)
			)
			(layer "F.SilkS")
		)
		(fp_line
			(start 0.7874 0.4064)
			(end -0.7874 0.4064)
			(stroke
				(width 0.1524)
				(type default)
			)
			(layer "F.SilkS")
		)
		(fp_line
			(start -0.67945 -0.305054)
			(end -0.12065 -0.305054)
			(stroke
				(width 0.1)
				(type default)
			)
			(layer "F.Fab")
		)
		(fp_line
			(start -0.67945 0.3048)
			(end -0.67945 -0.305054)
			(stroke
				(width 0.1)
				(type default)
			)
			(layer "F.Fab")
		)
		(fp_line
			(start -0.12065 -0.305054)
			(end -0.12065 -0.2794)
			(stroke
				(width 0.1)
				(type default)
			)
			(layer "F.Fab")
		)
		(fp_line
			(start -0.12065 -0.2794)
			(end 0.12065 -0.2794)
			(stroke
				(width 0.1)
				(type default)
			)
			(layer "F.Fab")
		)
		(fp_line
			(start -0.12065 0.2794)
			(end -0.12065 0.3048)
			(stroke
				(width 0.1)
				(type default)
			)
			(layer "F.Fab")
		)
		(fp_line
			(start -0.12065 0.3048)
			(end -0.67945 0.3048)
			(stroke
				(width 0.1)
				(type default)
			)
			(layer "F.Fab")
		)
		(fp_line
			(start 0.120396 0.2794)
			(end -0.12065 0.2794)
			(stroke
				(width 0.1)
				(type default)
			)
			(layer "F.Fab")
		)
		(fp_line
			(start 0.120396 0.3048)
			(end 0.120396 0.2794)
			(stroke
				(width 0.1)
				(type default)
			)
			(layer "F.Fab")
		)
		(fp_line
			(start 0.12065 -0.3048)
			(end 0.67945 -0.3048)
			(stroke
				(width 0.1)
				(type default)
			)
			(layer "F.Fab")
		)
		(fp_line
			(start 0.12065 -0.2794)
			(end 0.12065 -0.3048)
			(stroke
				(width 0.1)
				(type default)
			)
			(layer "F.Fab")
		)
		(fp_line
			(start 0.67945 -0.3048)
			(end 0.67945 0.3048)
			(stroke
				(width 0.1)
				(type default)
			)
			(layer "F.Fab")
		)
		(fp_line
			(start 0.67945 0.3048)
			(end 0.120396 0.3048)
			(stroke
				(width 0.1)
				(type default)
			)
			(layer "F.Fab")
		)
		(pad "1" smd circle
			(at -0.40005 0)
			(size 0 0)
			(layers "F.Cu" "F.Mask" "F.Paste")
			(net "P3V3_AUX")
		)
		(pad "2" smd circle
			(at 0.40005 0)
			(size 0 0)
			(layers "F.Cu" "F.Mask" "F.Paste")
			(net "SMB_LM75_0_3V3AUX_SDA")
		)
	)
	(footprint ""
		(layer "F.Cu")
		(at 369.455446 -30.084522 -90)
		(property "Reference" "R1425"
			(at 0 0 270)
			(layer "F.SilkS")
			(hide yes)
			(effects
				(font
					(size 1.27 1.27)
				)
			)
		)
		(property "Value" ""
			(at 0 0 270)
			(layer "F.Fab")
			(effects
				(font
					(size 1.27 1.27)
				)
			)
		)
		(duplicate_pad_numbers_are_jumpers no)
		(fp_line
			(start -0.7874 0.4064)
			(end -0.7874 -0.4064)
			(stroke
				(width 0.1524)
				(type default)
			)
			(layer "F.SilkS")
		)
		(fp_line
			(start 0.7874 0.4064)
			(end -0.7874 0.4064)
			(stroke
				(width 0.1524)
				(type default)
			)
			(layer "F.SilkS")
		)
		(fp_line
			(start -0.7874 -0.4064)
			(end 0.7874 -0.4064)
			(stroke
				(width 0.1524)
				(type default)
			)
			(layer "F.SilkS")
		)
		(fp_line
			(start 0.7874 -0.4064)
			(end 0.7874 0.4064)
			(stroke
				(width 0.1524)
				(type default)
			)
			(layer "F.SilkS")
		)
		(fp_line
			(start -0.67945 0.3048)
			(end -0.67945 -0.305054)
			(stroke
				(width 0.1)
				(type default)
			)
			(layer "F.Fab")
		)
		(fp_line
			(start -0.12065 0.3048)
			(end -0.67945 0.3048)
			(stroke
				(width 0.1)
				(type default)
			)
			(layer "F.Fab")
		)
		(fp_line
			(start 0.120396 0.3048)
			(end 0.120396 0.2794)
			(stroke
				(width 0.1)
				(type default)
			)
			(layer "F.Fab")
		)
		(fp_line
			(start 0.67945 0.3048)
			(end 0.120396 0.3048)
			(stroke
				(width 0.1)
				(type default)
			)
			(layer "F.Fab")
		)
		(fp_line
			(start -0.12065 0.2794)
			(end -0.12065 0.3048)
			(stroke
				(width 0.1)
				(type default)
			)
			(layer "F.Fab")
		)
		(fp_line
			(start 0.120396 0.2794)
			(end -0.12065 0.2794)
			(stroke
				(width 0.1)
				(type default)
			)
			(layer "F.Fab")
		)
		(fp_line
			(start -0.12065 -0.2794)
			(end 0.12065 -0.2794)
			(stroke
				(width 0.1)
				(type default)
			)
			(layer "F.Fab")
		)
		(fp_line
			(start 0.12065 -0.2794)
			(end 0.12065 -0.3048)
			(stroke
				(width 0.1)
				(type default)
			)
			(layer "F.Fab")
		)
		(fp_line
			(start 0.12065 -0.3048)
			(end 0.67945 -0.3048)
			(stroke
				(width 0.1)
				(type default)
			)
			(layer "F.Fab")
		)
		(fp_line
			(start 0.67945 -0.3048)
			(end 0.67945 0.3048)
			(stroke
				(width 0.1)
				(type default)
			)
			(layer "F.Fab")
		)
		(fp_line
			(start -0.67945 -0.305054)
			(end -0.12065 -0.305054)
			(stroke
				(width 0.1)
				(type default)
			)
			(layer "F.Fab")
		)
		(fp_line
			(start -0.12065 -0.305054)
			(end -0.12065 -0.2794)
			(stroke
				(width 0.1)
				(type default)
			)
			(layer "F.Fab")
		)
		(pad "1" smd circle
			(at -0.40005 0 270)
			(size 0 0)
			(layers "F.Cu" "F.Mask" "F.Paste")
			(net "UART_CPU0_SCM_LVC3_UART1_R_TX")
		)
		(pad "2" smd circle
			(at 0.40005 0 270)
			(size 0 0)
			(layers "F.Cu" "F.Mask" "F.Paste")
			(net "UART_CPU0_SCM_LVC3_UART1_TX")
		)
	)
)
